# S9S_MB_2U (Grand Teton) — schematic netlist excerpt (pin names and nets, part order shuffled) for the footprints in the layout excerpt that follows; sources: Cadence DE-HDL packaged netlist, KiCad conversion of 03242023_DA0F0TMBIJ0_F0T_Motherboard_J_brd_V01_OCP.brd

C1869  Q_CAP  0.1UF 25V 10% X7R  pkg 0402  page 167 : A = P2E_MB_BMC_RX_BUF_C_DN<0> ; B = P2E_MB_BMC_RX_BUF_DN<0>
PR3780  Q_RES  5.36K 1% CHIP  pkg 0402LF  page 156 : A = P3V3_OCP_CB_1 ; B = GND

(kicad_pcb
	(version 20260206)
	(generator "pcbnew")
	(generator_version "10.0")
	(general
		(thickness 1.6)
		(legacy_teardrops no)
	)
	(paper "A4")
	(title_block
		(title "03242023_DA0F0TMBIJ0_F0T_Motherboard_J_brd_V01_OCP.brd")
		(comment 1 "Grand Teton / footprints 83-84 of 6105")
	)
	(layers
		(0 "F.Cu" signal "TOP")
		(4 "In1.Cu" signal "GND")
		(6 "In2.Cu" signal "IN1")
		(8 "In3.Cu" signal "GND1")
		(10 "In4.Cu" signal "IN2")
		(12 "In5.Cu" signal "GND2")
		(14 "In6.Cu" signal "IN3")
		(16 "In7.Cu" signal "GND3")
		(18 "In8.Cu" signal "VCC")
		(20 "In9.Cu" signal "VCC1")
		(22 "In10.Cu" signal "GND4")
		(24 "In11.Cu" signal "IN4")
		(26 "In12.Cu" signal "GND5")
		(28 "In13.Cu" signal "IN5")
		(30 "In14.Cu" signal "GND6")
		(32 "In15.Cu" signal "IN6")
		(34 "In16.Cu" signal "GND7")
		(2 "B.Cu" signal "BOTTOM")
		(9 "F.Adhes" user "F.Adhesive")
		(11 "B.Adhes" user "B.Adhesive")
		(13 "F.Paste" user "Package Geometry/Pastemask Top")
		(15 "B.Paste" user "Package Geometry/Pastemask Bottom")
		(5 "F.SilkS" user "Ref Des/Silkscreen Top")
		(7 "B.SilkS" user "Ref Des/Silkscreen Bottom")
		(1 "F.Mask" user "Board Geometry/Soldermask Top")
		(3 "B.Mask" user "Board Geometry/Soldermask Bottom")
		(17 "Dwgs.User" user "User.Drawings")
		(19 "Cmts.User" user "User.Comments")
		(21 "Eco1.User" user "User.Eco1")
		(23 "Eco2.User" user "User.Eco2")
		(25 "Edge.Cuts" user "Board Geometry/Outline")
		(27 "Margin" user)
		(31 "F.CrtYd" user "Package Geometry/Place Bound Top")
		(29 "B.CrtYd" user "Package Geometry/Place Bound Bottom")
		(35 "F.Fab" user "Ref Des/Assembly Top")
		(33 "B.Fab" user "Ref Des/Assembly Bottom")
	)
	(footprint ""
		(layer "F.Cu")
		(at 22.460204 -385.778248 -90)
		(property "Reference" "C1869"
			(at 0 0 270)
			(layer "F.SilkS")
			(hide yes)
			(effects
				(font
					(size 1.27 1.27)
				)
			)
		)
		(property "Value" ""
			(at 0 0 270)
			(layer "F.Fab")
			(effects
				(font
					(size 1.27 1.27)
				)
			)
		)
		(duplicate_pad_numbers_are_jumpers no)
		(fp_line
			(start 0.7874 0.4064)
			(end -0.7874 0.4064)
			(stroke
				(width 0.1524)
				(type default)
			)
			(layer "F.SilkS")
		)
		(fp_line
			(start -0.7874 -0.4064)
			(end 0.000508 -0.4064)
			(stroke
				(width 0.1524)
				(type default)
			)
			(layer "F.SilkS")
		)
		(fp_line
			(start 0.7874 -0.4064)
			(end 0.7874 0.4064)
			(stroke
				(width 0.1524)
				(type default)
			)
			(layer "F.SilkS")
		)
		(fp_line
			(start -0.6858 0.3048)
			(end -0.6858 -0.3048)
			(stroke
				(width 0.1)
				(type default)
			)
			(layer "F.Fab")
		)
		(fp_line
			(start -0.1016 0.3048)
			(end -0.6858 0.3048)
			(stroke
				(width 0.1)
				(type default)
			)
			(layer "F.Fab")
		)
		(fp_line
			(start 0.1016 0.3048)
			(end 0.1016 0.2794)
			(stroke
				(width 0.1)
				(type default)
			)
			(layer "F.Fab")
		)
		(fp_line
			(start 0.6858 0.3048)
			(end 0.1016 0.3048)
			(stroke
				(width 0.1)
				(type default)
			)
			(layer "F.Fab")
		)
		(fp_line
			(start -0.1016 0.2794)
			(end -0.1016 0.3048)
			(stroke
				(width 0.1)
				(type default)
			)
			(layer "F.Fab")
		)
		(fp_line
			(start 0.1016 0.2794)
			(end -0.1016 0.2794)
			(stroke
				(width 0.1)
				(type default)
			)
			(layer "F.Fab")
		)
		(fp_line
			(start -0.1016 -0.2794)
			(end 0.1016 -0.2794)
			(stroke
				(width 0.1)
				(type default)
			)
			(layer "F.Fab")
		)
		(fp_line
			(start 0.1016 -0.2794)
			(end 0.1016 -0.3048)
			(stroke
				(width 0.1)
				(type default)
			)
			(layer "F.Fab")
		)
		(fp_line
			(start -0.6858 -0.3048)
			(end -0.1016 -0.3048)
			(stroke
				(width 0.1)
				(type default)
			)
			(layer "F.Fab")
		)
		(fp_line
			(start -0.1016 -0.3048)
			(end -0.1016 -0.2794)
			(stroke
				(width 0.1)
				(type default)
			)
			(layer "F.Fab")
		)
		(fp_line
			(start 0.1016 -0.3048)
			(end 0.6858 -0.3048)
			(stroke
				(width 0.1)
				(type default)
			)
			(layer "F.Fab")
		)
		(fp_line
			(start 0.6858 -0.3048)
			(end 0.6858 0.3048)
			(stroke
				(width 0.1)
				(type default)
			)
			(layer "F.Fab")
		)
		(pad "1" smd rect
			(at -0.40005 0 90)
			(size 0.4572 0.508)
			(layers "F.Cu" "F.Mask" "F.Paste")
			(net "P2E_MB_BMC_RX_BUF_C_DN<0>")
		)
		(pad "2" smd rect
			(at 0.40005 0 90)
			(size 0.4572 0.508)
			(layers "F.Cu" "F.Mask" "F.Paste")
			(net "P2E_MB_BMC_RX_BUF_DN<0>")
		)
	)
	(footprint ""
		(layer "F.Cu")
		(at 432.085496 -109.13745 90)
		(property "Reference" "PR3780"
			(at 0 0 90)
			(layer "F.SilkS")
			(hide yes)
			(effects
				(font
					(size 1.27 1.27)
				)
			)
		)
		(property "Value" ""
			(at 0 0 90)
			(layer "F.Fab")
			(effects
				(font
					(size 1.27 1.27)
				)
			)
		)
		(duplicate_pad_numbers_are_jumpers no)
		(fp_line
			(start 0.7874 -0.4064)
			(end 0.7874 0.4064)
			(stroke
				(width 0.1524)
				(type default)
			)
			(layer "F.SilkS")
		)
		(fp_line
			(start -0.7874 -0.4064)
			(end 0.7874 -0.4064)
			(stroke
				(width 0.1524)
				(type default)
			)
			(layer "F.SilkS")
		)
		(fp_line
			(start 0.7874 0.4064)
			(end -0.7874 0.4064)
			(stroke
				(width 0.1524)
				(type default)
			)
			(layer "F.SilkS")
		)
		(fp_line
			(start -0.7874 0.4064)
			(end -0.7874 -0.4064)
			(stroke
				(width 0.1524)
				(type default)
			)
			(layer "F.SilkS")
		)
		(fp_line
			(start -0.12065 -0.305054)
			(end -0.12065 -0.2794)
			(stroke
				(width 0.1)
				(type default)
			)
			(layer "F.Fab")
		)
		(fp_line
			(start -0.67945 -0.305054)
			(end -0.12065 -0.305054)
			(stroke
				(width 0.1)
				(type default)
			)
			(layer "F.Fab")
		)
		(fp_line
			(start 0.67945 -0.3048)
			(end 0.67945 0.3048)
			(stroke
				(width 0.1)
				(type default)
			)
			(layer "F.Fab")
		)
		(fp_line
			(start 0.12065 -0.3048)
			(end 0.67945 -0.3048)
			(stroke
				(width 0.1)
				(type default)
			)
			(layer "F.Fab")
		)
		(fp_line
			(start 0.12065 -0.2794)
			(end 0.12065 -0.3048)
			(stroke
				(width 0.1)
				(type default)
			)
			(layer "F.Fab")
		)
		(fp_line
			(start -0.12065 -0.2794)
			(end 0.12065 -0.2794)
			(stroke
				(width 0.1)
				(type default)
			)
			(layer "F.Fab")
		)
		(fp_line
			(start 0.120396 0.2794)
			(end -0.12065 0.2794)
			(stroke
				(width 0.1)
				(type default)
			)
			(layer "F.Fab")
		)
		(fp_line
			(start -0.12065 0.2794)
			(end -0.12065 0.3048)
			(stroke
				(width 0.1)
				(type default)
			)
			(layer "F.Fab")
		)
		(fp_line
			(start 0.67945 0.3048)
			(end 0.120396 0.3048)
			(stroke
				(width 0.1)
				(type default)
			)
			(layer "F.Fab")
		)
		(fp_line
			(start 0.120396 0.3048)
			(end 0.120396 0.2794)
			(stroke
				(width 0.1)
				(type default)
			)
			(layer "F.Fab")
		)
		(fp_line
			(start -0.12065 0.3048)
			(end -0.67945 0.3048)
			(stroke
				(width 0.1)
				(type default)
			)
			(layer "F.Fab")
		)
		(fp_line
			(start -0.67945 0.3048)
			(end -0.67945 -0.305054)
			(stroke
				(width 0.1)
				(type default)
			)
			(layer "F.Fab")
		)
		(pad "1" smd circle
			(at -0.40005 0 90)
			(size 0 0)
			(layers "F.Cu" "F.Mask" "F.Paste")
			(net "P3V3_OCP_CB_1")
		)
		(pad "2" smd circle
			(at 0.40005 0 90)
			(size 0 0)
			(layers "F.Cu" "F.Mask" "F.Paste")
			(net "GND")
		)
	)
)
